FILE_TYPE=LIBRARY_PARTS;
TIME=' Created/Modified on Thu Jul 12 16:13:51 2007' ;
primitive 'PI3B3257A','PI3B3257A_TSSOPLF';
  pin
    'VCC':
      PIN_NUMBER='(16)';
      PIN_TYPE='POWER';
      NO_LOAD_CHECK='BOTH';
      NO_IO_CHECK='BOTH';
      ALLOW_CONNECT='TRUE';
    'GND':
      PIN_NUMBER='(8)';
      PIN_TYPE='POWER';
      NO_LOAD_CHECK='BOTH';
      NO_IO_CHECK='BOTH';
      ALLOW_CONNECT='TRUE';
    'EN':
      PIN_NUMBER='(15)';
      INPUT_LOAD='(-0.01,0.01)';
    'S':
      PIN_NUMBER='(1)';
      INPUT_LOAD='(-0.01,0.01)';
      OUTPUT_LOAD='(1.0,-1.0)';
      OUTPUT_TYPE='(TS,TS)';
      BIDIRECTIONAL='TRUE';
    'YA':
      PIN_NUMBER='(4)';
      INPUT_LOAD='(-0.01,0.01)';
      OUTPUT_LOAD='(1.0,-1.0)';
      OUTPUT_TYPE='(TS,TS)';
      BIDIRECTIONAL='TRUE';
    'YB':
      PIN_NUMBER='(7)';
      INPUT_LOAD='(-0.01,0.01)';
      OUTPUT_LOAD='(1.0,-1.0)';
      OUTPUT_TYPE='(TS,TS)';
      BIDIRECTIONAL='TRUE';
    'YC':
      PIN_NUMBER='(9)';
      INPUT_LOAD='(-0.01,0.01)';
      OUTPUT_LOAD='(1.0,-1.0)';
      OUTPUT_TYPE='(TS,TS)';
      BIDIRECTIONAL='TRUE';
    'YD':
      PIN_NUMBER='(12)';
      INPUT_LOAD='(-0.01,0.01)';
      OUTPUT_LOAD='(1.0,-1.0)';
      OUTPUT_TYPE='(TS,TS)';
      BIDIRECTIONAL='TRUE';
    'IA0':
      PIN_NUMBER='(2)';
      INPUT_LOAD='(-0.01,0.01)';
      OUTPUT_LOAD='(1.0,-1.0)';
      OUTPUT_TYPE='(TS,TS)';
      BIDIRECTIONAL='TRUE';
    'IA1':
      PIN_NUMBER='(3)';
      INPUT_LOAD='(-0.01,0.01)';
      OUTPUT_LOAD='(1.0,-1.0)';
      OUTPUT_TYPE='(TS,TS)';
      BIDIRECTIONAL='TRUE';
    'IB0':
      PIN_NUMBER='(5)';
      INPUT_LOAD='(-0.01,0.01)';
      OUTPUT_LOAD='(1.0,-1.0)';
      OUTPUT_TYPE='(TS,TS)';
      BIDIRECTIONAL='TRUE';
    'IB1':
      PIN_NUMBER='(6)';
      INPUT_LOAD='(-0.01,0.01)';
      OUTPUT_LOAD='(1.0,-1.0)';
      OUTPUT_TYPE='(TS,TS)';
      BIDIRECTIONAL='TRUE';
    'IC0':
      PIN_NUMBER='(11)';
      INPUT_LOAD='(-0.01,0.01)';
      OUTPUT_LOAD='(1.0,-1.0)';
      OUTPUT_TYPE='(TS,TS)';
      BIDIRECTIONAL='TRUE';
    'IC1':
      PIN_NUMBER='(10)';
      INPUT_LOAD='(-0.01,0.01)';
      OUTPUT_LOAD='(1.0,-1.0)';
      OUTPUT_TYPE='(TS,TS)';
      BIDIRECTIONAL='TRUE';
    'ID0':
      PIN_NUMBER='(14)';
      INPUT_LOAD='(-0.01,0.01)';
      OUTPUT_LOAD='(1.0,-1.0)';
      OUTPUT_TYPE='(TS,TS)';
      BIDIRECTIONAL='TRUE';
    'ID1':
      PIN_NUMBER='(13)';
      INPUT_LOAD='(-0.01,0.01)';
      OUTPUT_LOAD='(1.0,-1.0)';
      OUTPUT_TYPE='(TS,TS)';
      BIDIRECTIONAL='TRUE';
  end_pin;
  body
    CLASS='IC';
    PART_NAME='PI3B3257A';
    PHYS_DES_PREFIX='U';
  end_body;
end_primitive;
END.
